(kicad_pcb
	(version 20260206)
	(generator "pcbnew")
	(generator_version "10.0")
	(general
		(thickness 1.6)
		(legacy_teardrops no)
	)
	(paper "A4")
	(title_block
		(title "12092022_DA0F0TFB6D0_F0T_FAN_BOARD_MP5048_D_brd_v02_OCP.brd")
		(comment 1 "Grand Teton / footprints 542-547 of 924")
	)
	(layers
		(0 "F.Cu" signal "TOP")
		(4 "In1.Cu" signal "GND")
		(6 "In2.Cu" signal "IN1")
		(8 "In3.Cu" signal "IN2")
		(10 "In4.Cu" signal "GND1")
		(2 "B.Cu" signal "BOTTOM")
		(9 "F.Adhes" user "F.Adhesive")
		(11 "B.Adhes" user "B.Adhesive")
		(13 "F.Paste" user "Package Geometry/Pastemask Top")
		(15 "B.Paste" user "Package Geometry/Pastemask Bottom")
		(5 "F.SilkS" user "Ref Des/Silkscreen Top")
		(7 "B.SilkS" user "Ref Des/Silkscreen Bottom")
		(1 "F.Mask" user "Board Geometry/Soldermask Top")
		(3 "B.Mask" user "Board Geometry/Soldermask Bottom")
		(17 "Dwgs.User" user "User.Drawings")
		(19 "Cmts.User" user "User.Comments")
		(21 "Eco1.User" user "User.Eco1")
		(23 "Eco2.User" user "User.Eco2")
		(25 "Edge.Cuts" user "Board Geometry/Outline")
		(27 "Margin" user)
		(31 "F.CrtYd" user "Package Geometry/Place Bound Top")
		(29 "B.CrtYd" user "Package Geometry/Place Bound Bottom")
		(35 "F.Fab" user "Ref Des/Assembly Top")
		(33 "B.Fab" user "Ref Des/Assembly Bottom")
	)
	(footprint ""
		(layer "F.Cu")
		(at 45.085 -181.102 180)
		(property "Reference" "R519"
			(at 0 0 180)
			(layer "F.SilkS")
			(hide yes)
			(effects
				(font
					(size 1.27 1.27)
				)
			)
		)
		(property "Value" ""
			(at 0 0 180)
			(layer "F.Fab")
			(effects
				(font
					(size 1.27 1.27)
				)
			)
		)
		(duplicate_pad_numbers_are_jumpers no)
		(fp_line
			(start 0.7874 0.4064)
			(end -0.7874 0.4064)
			(stroke
				(width 0.1524)
				(type default)
			)
			(layer "F.SilkS")
		)
		(fp_line
			(start 0.7874 -0.4064)
			(end 0.7874 0.4064)
			(stroke
				(width 0.1524)
				(type default)
			)
			(layer "F.SilkS")
		)
		(fp_line
			(start -0.7874 0.4064)
			(end -0.7874 -0.4064)
			(stroke
				(width 0.1524)
				(type default)
			)
			(layer "F.SilkS")
		)
		(fp_line
			(start -0.7874 -0.4064)
			(end 0.7874 -0.4064)
			(stroke
				(width 0.1524)
				(type default)
			)
			(layer "F.SilkS")
		)
		(fp_line
			(start 0.67945 0.3048)
			(end 0.120396 0.3048)
			(stroke
				(width 0.1)
				(type default)
			)
			(layer "F.Fab")
		)
		(fp_line
			(start 0.67945 -0.3048)
			(end 0.67945 0.3048)
			(stroke
				(width 0.1)
				(type default)
			)
			(layer "F.Fab")
		)
		(fp_line
			(start 0.12065 -0.2794)
			(end 0.12065 -0.3048)
			(stroke
				(width 0.1)
				(type default)
			)
			(layer "F.Fab")
		)
		(fp_line
			(start 0.12065 -0.3048)
			(end 0.67945 -0.3048)
			(stroke
				(width 0.1)
				(type default)
			)
			(layer "F.Fab")
		)
		(fp_line
			(start 0.120396 0.3048)
			(end 0.120396 0.2794)
			(stroke
				(width 0.1)
				(type default)
			)
			(layer "F.Fab")
		)
		(fp_line
			(start 0.120396 0.2794)
			(end -0.12065 0.2794)
			(stroke
				(width 0.1)
				(type default)
			)
			(layer "F.Fab")
		)
		(fp_line
			(start -0.12065 0.3048)
			(end -0.67945 0.3048)
			(stroke
				(width 0.1)
				(type default)
			)
			(layer "F.Fab")
		)
		(fp_line
			(start -0.12065 0.2794)
			(end -0.12065 0.3048)
			(stroke
				(width 0.1)
				(type default)
			)
			(layer "F.Fab")
		)
		(fp_line
			(start -0.12065 -0.2794)
			(end 0.12065 -0.2794)
			(stroke
				(width 0.1)
				(type default)
			)
			(layer "F.Fab")
		)
		(fp_line
			(start -0.12065 -0.305054)
			(end -0.12065 -0.2794)
			(stroke
				(width 0.1)
				(type default)
			)
			(layer "F.Fab")
		)
		(fp_line
			(start -0.67945 0.3048)
			(end -0.67945 -0.305054)
			(stroke
				(width 0.1)
				(type default)
			)
			(layer "F.Fab")
		)
		(fp_line
			(start -0.67945 -0.305054)
			(end -0.12065 -0.305054)
			(stroke
				(width 0.1)
				(type default)
			)
			(layer "F.Fab")
		)
		(pad "1" smd circle
			(at -0.40005 0 180)
			(size 0 0)
			(layers "F.Cu" "F.Mask" "F.Paste")
			(net "GND")
		)
		(pad "2" smd circle
			(at 0.40005 0 180)
			(size 0 0)
			(layers "F.Cu" "F.Mask" "F.Paste")
			(net "PD_FAN_BUFF_INPUT_U336E")
		)
	)
	(footprint ""
		(layer "F.Cu")
		(at 18.415 -181.61 180)
		(property "Reference" "R2360"
			(at 0 0 180)
			(layer "F.SilkS")
			(hide yes)
			(effects
				(font
					(size 1.27 1.27)
				)
			)
		)
		(property "Value" ""
			(at 0 0 180)
			(layer "F.Fab")
			(effects
				(font
					(size 1.27 1.27)
				)
			)
		)
		(duplicate_pad_numbers_are_jumpers no)
		(fp_line
			(start 0.7874 0.4064)
			(end -0.7874 0.4064)
			(stroke
				(width 0.1524)
				(type default)
			)
			(layer "F.SilkS")
		)
		(fp_line
			(start 0.7874 -0.4064)
			(end 0.7874 0.4064)
			(stroke
				(width 0.1524)
				(type default)
			)
			(layer "F.SilkS")
		)
		(fp_line
			(start -0.7874 0.4064)
			(end -0.7874 -0.4064)
			(stroke
				(width 0.1524)
				(type default)
			)
			(layer "F.SilkS")
		)
		(fp_line
			(start -0.7874 -0.4064)
			(end 0.7874 -0.4064)
			(stroke
				(width 0.1524)
				(type default)
			)
			(layer "F.SilkS")
		)
		(fp_line
			(start 0.67945 0.3048)
			(end 0.120396 0.3048)
			(stroke
				(width 0.1)
				(type default)
			)
			(layer "F.Fab")
		)
		(fp_line
			(start 0.67945 -0.3048)
			(end 0.67945 0.3048)
			(stroke
				(width 0.1)
				(type default)
			)
			(layer "F.Fab")
		)
		(fp_line
			(start 0.12065 -0.2794)
			(end 0.12065 -0.3048)
			(stroke
				(width 0.1)
				(type default)
			)
			(layer "F.Fab")
		)
		(fp_line
			(start 0.12065 -0.3048)
			(end 0.67945 -0.3048)
			(stroke
				(width 0.1)
				(type default)
			)
			(layer "F.Fab")
		)
		(fp_line
			(start 0.120396 0.3048)
			(end 0.120396 0.2794)
			(stroke
				(width 0.1)
				(type default)
			)
			(layer "F.Fab")
		)
		(fp_line
			(start 0.120396 0.2794)
			(end -0.12065 0.2794)
			(stroke
				(width 0.1)
				(type default)
			)
			(layer "F.Fab")
		)
		(fp_line
			(start -0.12065 0.3048)
			(end -0.67945 0.3048)
			(stroke
				(width 0.1)
				(type default)
			)
			(layer "F.Fab")
		)
		(fp_line
			(start -0.12065 0.2794)
			(end -0.12065 0.3048)
			(stroke
				(width 0.1)
				(type default)
			)
			(layer "F.Fab")
		)
		(fp_line
			(start -0.12065 -0.2794)
			(end 0.12065 -0.2794)
			(stroke
				(width 0.1)
				(type default)
			)
			(layer "F.Fab")
		)
		(fp_line
			(start -0.12065 -0.305054)
			(end -0.12065 -0.2794)
			(stroke
				(width 0.1)
				(type default)
			)
			(layer "F.Fab")
		)
		(fp_line
			(start -0.67945 0.3048)
			(end -0.67945 -0.305054)
			(stroke
				(width 0.1)
				(type default)
			)
			(layer "F.Fab")
		)
		(fp_line
			(start -0.67945 -0.305054)
			(end -0.12065 -0.305054)
			(stroke
				(width 0.1)
				(type default)
			)
			(layer "F.Fab")
		)
		(pad "1" smd circle
			(at -0.40005 0 180)
			(size 0 0)
			(layers "F.Cu" "F.Mask" "F.Paste")
			(net "P3V3_AUX")
		)
		(pad "2" smd circle
			(at 0.40005 0 180)
			(size 0 0)
			(layers "F.Cu" "F.Mask" "F.Paste")
			(net "PCA9555_MB0_A0")
		)
	)
	(footprint ""
		(layer "F.Cu")
		(at 25.527 -132.461)
		(property "Reference" "R4942"
			(at 0 0 0)
			(layer "F.SilkS")
			(hide yes)
			(effects
				(font
					(size 1.27 1.27)
				)
			)
		)
		(property "Value" ""
			(at 0 0 0)
			(layer "F.Fab")
			(effects
				(font
					(size 1.27 1.27)
				)
			)
		)
		(duplicate_pad_numbers_are_jumpers no)
		(fp_line
			(start -0.7874 -0.4064)
			(end 0.7874 -0.4064)
			(stroke
				(width 0.1524)
				(type default)
			)
			(layer "F.SilkS")
		)
		(fp_line
			(start -0.7874 0.4064)
			(end -0.7874 -0.4064)
			(stroke
				(width 0.1524)
				(type default)
			)
			(layer "F.SilkS")
		)
		(fp_line
			(start 0.7874 -0.4064)
			(end 0.7874 0.4064)
			(stroke
				(width 0.1524)
				(type default)
			)
			(layer "F.SilkS")
		)
		(fp_line
			(start 0.7874 0.4064)
			(end -0.7874 0.4064)
			(stroke
				(width 0.1524)
				(type default)
			)
			(layer "F.SilkS")
		)
		(fp_line
			(start -0.67945 -0.305054)
			(end -0.12065 -0.305054)
			(stroke
				(width 0.1)
				(type default)
			)
			(layer "F.Fab")
		)
		(fp_line
			(start -0.67945 0.3048)
			(end -0.67945 -0.305054)
			(stroke
				(width 0.1)
				(type default)
			)
			(layer "F.Fab")
		)
		(fp_line
			(start -0.12065 -0.305054)
			(end -0.12065 -0.2794)
			(stroke
				(width 0.1)
				(type default)
			)
			(layer "F.Fab")
		)
		(fp_line
			(start -0.12065 -0.2794)
			(end 0.12065 -0.2794)
			(stroke
				(width 0.1)
				(type default)
			)
			(layer "F.Fab")
		)
		(fp_line
			(start -0.12065 0.2794)
			(end -0.12065 0.3048)
			(stroke
				(width 0.1)
				(type default)
			)
			(layer "F.Fab")
		)
		(fp_line
			(start -0.12065 0.3048)
			(end -0.67945 0.3048)
			(stroke
				(width 0.1)
				(type default)
			)
			(layer "F.Fab")
		)
		(fp_line
			(start 0.120396 0.2794)
			(end -0.12065 0.2794)
			(stroke
				(width 0.1)
				(type default)
			)
			(layer "F.Fab")
		)
		(fp_line
			(start 0.120396 0.3048)
			(end 0.120396 0.2794)
			(stroke
				(width 0.1)
				(type default)
			)
			(layer "F.Fab")
		)
		(fp_line
			(start 0.12065 -0.3048)
			(end 0.67945 -0.3048)
			(stroke
				(width 0.1)
				(type default)
			)
			(layer "F.Fab")
		)
		(fp_line
			(start 0.12065 -0.2794)
			(end 0.12065 -0.3048)
			(stroke
				(width 0.1)
				(type default)
			)
			(layer "F.Fab")
		)
		(fp_line
			(start 0.67945 -0.3048)
			(end 0.67945 0.3048)
			(stroke
				(width 0.1)
				(type default)
			)
			(layer "F.Fab")
		)
		(fp_line
			(start 0.67945 0.3048)
			(end 0.120396 0.3048)
			(stroke
				(width 0.1)
				(type default)
			)
			(layer "F.Fab")
		)
		(pad "1" smd circle
			(at -0.40005 0)
			(size 0 0)
			(layers "F.Cu" "F.Mask" "F.Paste")
			(net "GND")
		)
		(pad "2" smd circle
			(at 0.40005 0)
			(size 0 0)
			(layers "F.Cu" "F.Mask" "F.Paste")
			(net "MAX31790_U317_PWM_START0")
		)
	)
	(footprint ""
		(layer "F.Cu")
		(at 11.445494 -71.812912)
		(property "Reference" "C2063"
			(at 0 0 0)
			(layer "F.SilkS")
			(hide yes)
			(effects
				(font
					(size 1.27 1.27)
				)
			)
		)
		(property "Value" ""
			(at 0 0 0)
			(layer "F.Fab")
			(effects
				(font
					(size 1.27 1.27)
				)
			)
		)
		(duplicate_pad_numbers_are_jumpers no)
		(fp_line
			(start -0.7874 -0.4064)
			(end 0.7874 -0.4064)
			(stroke
				(width 0.1524)
				(type default)
			)
			(layer "F.SilkS")
		)
		(fp_line
			(start -0.7874 0.4064)
			(end -0.7874 -0.4064)
			(stroke
				(width 0.1524)
				(type default)
			)
			(layer "F.SilkS")
		)
		(fp_line
			(start 0.7874 -0.4064)
			(end 0.7874 0.4064)
			(stroke
				(width 0.1524)
				(type default)
			)
			(layer "F.SilkS")
		)
		(fp_line
			(start 0.7874 0.4064)
			(end -0.7874 0.4064)
			(stroke
				(width 0.1524)
				(type default)
			)
			(layer "F.SilkS")
		)
		(fp_line
			(start -0.67945 -0.305054)
			(end -0.12065 -0.305054)
			(stroke
				(width 0.1)
				(type default)
			)
			(layer "F.Fab")
		)
		(fp_line
			(start -0.67945 0.3048)
			(end -0.67945 -0.305054)
			(stroke
				(width 0.1)
				(type default)
			)
			(layer "F.Fab")
		)
		(fp_line
			(start -0.12065 -0.305054)
			(end -0.12065 -0.2794)
			(stroke
				(width 0.1)
				(type default)
			)
			(layer "F.Fab")
		)
		(fp_line
			(start -0.12065 -0.2794)
			(end 0.12065 -0.2794)
			(stroke
				(width 0.1)
				(type default)
			)
			(layer "F.Fab")
		)
		(fp_line
			(start -0.12065 0.2794)
			(end -0.12065 0.3048)
			(stroke
				(width 0.1)
				(type default)
			)
			(layer "F.Fab")
		)
		(fp_line
			(start -0.12065 0.3048)
			(end -0.67945 0.3048)
			(stroke
				(width 0.1)
				(type default)
			)
			(layer "F.Fab")
		)
		(fp_line
			(start 0.120396 0.2794)
			(end -0.12065 0.2794)
			(stroke
				(width 0.1)
				(type default)
			)
			(layer "F.Fab")
		)
		(fp_line
			(start 0.120396 0.3048)
			(end 0.120396 0.2794)
			(stroke
				(width 0.1)
				(type default)
			)
			(layer "F.Fab")
		)
		(fp_line
			(start 0.12065 -0.3048)
			(end 0.67945 -0.3048)
			(stroke
				(width 0.1)
				(type default)
			)
			(layer "F.Fab")
		)
		(fp_line
			(start 0.12065 -0.2794)
			(end 0.12065 -0.3048)
			(stroke
				(width 0.1)
				(type default)
			)
			(layer "F.Fab")
		)
		(fp_line
			(start 0.67945 -0.3048)
			(end 0.67945 0.3048)
			(stroke
				(width 0.1)
				(type default)
			)
			(layer "F.Fab")
		)
		(fp_line
			(start 0.67945 0.3048)
			(end 0.120396 0.3048)
			(stroke
				(width 0.1)
				(type default)
			)
			(layer "F.Fab")
		)
		(pad "1" smd circle
			(at -0.40005 0)
			(size 0 0)
			(layers "F.Cu" "F.Mask" "F.Paste")
			(net "P3V3_AUX")
		)
		(pad "2" smd circle
			(at 0.40005 0)
			(size 0 0)
			(layers "F.Cu" "F.Mask" "F.Paste")
			(net "GND")
		)
	)
	(footprint ""
		(layer "F.Cu")
		(at 19.558 -114.681 -90)
		(property "Reference" "R5363"
			(at 0 0 270)
			(layer "F.SilkS")
			(hide yes)
			(effects
				(font
					(size 1.27 1.27)
				)
			)
		)
		(property "Value" ""
			(at 0 0 270)
			(layer "F.Fab")
			(effects
				(font
					(size 1.27 1.27)
				)
			)
		)
		(duplicate_pad_numbers_are_jumpers no)
		(fp_line
			(start -0.7874 0.4064)
			(end -0.7874 -0.4064)
			(stroke
				(width 0.1524)
				(type default)
			)
			(layer "F.SilkS")
		)
		(fp_line
			(start 0.7874 0.4064)
			(end -0.7874 0.4064)
			(stroke
				(width 0.1524)
				(type default)
			)
			(layer "F.SilkS")
		)
		(fp_line
			(start -0.7874 -0.4064)
			(end 0.7874 -0.4064)
			(stroke
				(width 0.1524)
				(type default)
			)
			(layer "F.SilkS")
		)
		(fp_line
			(start 0.7874 -0.4064)
			(end 0.7874 0.4064)
			(stroke
				(width 0.1524)
				(type default)
			)
			(layer "F.SilkS")
		)
		(fp_line
			(start -0.67945 0.3048)
			(end -0.67945 -0.305054)
			(stroke
				(width 0.1)
				(type default)
			)
			(layer "F.Fab")
		)
		(fp_line
			(start -0.12065 0.3048)
			(end -0.67945 0.3048)
			(stroke
				(width 0.1)
				(type default)
			)
			(layer "F.Fab")
		)
		(fp_line
			(start 0.120396 0.3048)
			(end 0.120396 0.2794)
			(stroke
				(width 0.1)
				(type default)
			)
			(layer "F.Fab")
		)
		(fp_line
			(start 0.67945 0.3048)
			(end 0.120396 0.3048)
			(stroke
				(width 0.1)
				(type default)
			)
			(layer "F.Fab")
		)
		(fp_line
			(start -0.12065 0.2794)
			(end -0.12065 0.3048)
			(stroke
				(width 0.1)
				(type default)
			)
			(layer "F.Fab")
		)
		(fp_line
			(start 0.120396 0.2794)
			(end -0.12065 0.2794)
			(stroke
				(width 0.1)
				(type default)
			)
			(layer "F.Fab")
		)
		(fp_line
			(start -0.12065 -0.2794)
			(end 0.12065 -0.2794)
			(stroke
				(width 0.1)
				(type default)
			)
			(layer "F.Fab")
		)
		(fp_line
			(start 0.12065 -0.2794)
			(end 0.12065 -0.3048)
			(stroke
				(width 0.1)
				(type default)
			)
			(layer "F.Fab")
		)
		(fp_line
			(start 0.12065 -0.3048)
			(end 0.67945 -0.3048)
			(stroke
				(width 0.1)
				(type default)
			)
			(layer "F.Fab")
		)
		(fp_line
			(start 0.67945 -0.3048)
			(end 0.67945 0.3048)
			(stroke
				(width 0.1)
				(type default)
			)
			(layer "F.Fab")
		)
		(fp_line
			(start -0.67945 -0.305054)
			(end -0.12065 -0.305054)
			(stroke
				(width 0.1)
				(type default)
			)
			(layer "F.Fab")
		)
		(fp_line
			(start -0.12065 -0.305054)
			(end -0.12065 -0.2794)
			(stroke
				(width 0.1)
				(type default)
			)
			(layer "F.Fab")
		)
		(pad "1" smd circle
			(at -0.40005 0 270)
			(size 0 0)
			(layers "F.Cu" "F.Mask" "F.Paste")
			(net "P3V3_AUX")
		)
		(pad "2" smd circle
			(at 0.40005 0 270)
			(size 0 0)
			(layers "F.Cu" "F.Mask" "F.Paste")
			(net "FAN_5_OK_R_LED")
		)
	)
	(footprint ""
		(layer "F.Cu")
		(at 17.907 -170.815 180)
		(property "Reference" "R5500"
			(at 0 0 180)
			(layer "F.SilkS")
			(hide yes)
			(effects
				(font
					(size 1.27 1.27)
				)
			)
		)
		(property "Value" ""
			(at 0 0 180)
			(layer "F.Fab")
			(effects
				(font
					(size 1.27 1.27)
				)
			)
		)
		(duplicate_pad_numbers_are_jumpers no)
		(fp_line
			(start 0.7874 0.4064)
			(end -0.7874 0.4064)
			(stroke
				(width 0.1524)
				(type default)
			)
			(layer "F.SilkS")
		)
		(fp_line
			(start 0.7874 -0.4064)
			(end 0.7874 0.4064)
			(stroke
				(width 0.1524)
				(type default)
			)
			(layer "F.SilkS")
		)
		(fp_line
			(start -0.7874 0.4064)
			(end -0.7874 -0.4064)
			(stroke
				(width 0.1524)
				(type default)
			)
			(layer "F.SilkS")
		)
		(fp_line
			(start -0.7874 -0.4064)
			(end 0.7874 -0.4064)
			(stroke
				(width 0.1524)
				(type default)
			)
			(layer "F.SilkS")
		)
		(fp_line
			(start 0.67945 0.3048)
			(end 0.120396 0.3048)
			(stroke
				(width 0.1)
				(type default)
			)
			(layer "F.Fab")
		)
		(fp_line
			(start 0.67945 -0.3048)
			(end 0.67945 0.3048)
			(stroke
				(width 0.1)
				(type default)
			)
			(layer "F.Fab")
		)
		(fp_line
			(start 0.12065 -0.2794)
			(end 0.12065 -0.3048)
			(stroke
				(width 0.1)
				(type default)
			)
			(layer "F.Fab")
		)
		(fp_line
			(start 0.12065 -0.3048)
			(end 0.67945 -0.3048)
			(stroke
				(width 0.1)
				(type default)
			)
			(layer "F.Fab")
		)
		(fp_line
			(start 0.120396 0.3048)
			(end 0.120396 0.2794)
			(stroke
				(width 0.1)
				(type default)
			)
			(layer "F.Fab")
		)
		(fp_line
			(start 0.120396 0.2794)
			(end -0.12065 0.2794)
			(stroke
				(width 0.1)
				(type default)
			)
			(layer "F.Fab")
		)
		(fp_line
			(start -0.12065 0.3048)
			(end -0.67945 0.3048)
			(stroke
				(width 0.1)
				(type default)
			)
			(layer "F.Fab")
		)
		(fp_line
			(start -0.12065 0.2794)
			(end -0.12065 0.3048)
			(stroke
				(width 0.1)
				(type default)
			)
			(layer "F.Fab")
		)
		(fp_line
			(start -0.12065 -0.2794)
			(end 0.12065 -0.2794)
			(stroke
				(width 0.1)
				(type default)
			)
			(layer "F.Fab")
		)
		(fp_line
			(start -0.12065 -0.305054)
			(end -0.12065 -0.2794)
			(stroke
				(width 0.1)
				(type default)
			)
			(layer "F.Fab")
		)
		(fp_line
			(start -0.67945 0.3048)
			(end -0.67945 -0.305054)
			(stroke
				(width 0.1)
				(type default)
			)
			(layer "F.Fab")
		)
		(fp_line
			(start -0.67945 -0.305054)
			(end -0.12065 -0.305054)
			(stroke
				(width 0.1)
				(type default)
			)
			(layer "F.Fab")
		)
		(pad "1" smd circle
			(at -0.40005 0 180)
			(size 0 0)
			(layers "F.Cu" "F.Mask" "F.Paste")
			(net "FAN_5_PRESENT_R_N")
		)
		(pad "2" smd circle
			(at 0.40005 0 180)
			(size 0 0)
			(layers "F.Cu" "F.Mask" "F.Paste")
			(net "FAN_5_PRESENT_N")
		)
	)
)
